(kicad_pcb
	(version 20260206)
	(generator "pcbnew")
	(generator_version "10.0")
	(general
		(thickness 1.6)
		(legacy_teardrops no)
	)
	(paper "A4")
	(title_block
		(title "04192023_DAF0TMB3IC0_F0TG_MB_C_brd_V02_OCP.brd")
		(comment 1 "Grand Teton / footprints 5400-5406 of 8354")
	)
	(layers
		(0 "F.Cu" signal "TOP")
		(4 "In1.Cu" signal "GND")
		(6 "In2.Cu" signal "IN1")
		(8 "In3.Cu" signal "GND1")
		(10 "In4.Cu" signal "IN2")
		(12 "In5.Cu" signal "GND2")
		(14 "In6.Cu" signal "IN3")
		(16 "In7.Cu" signal "GND3")
		(18 "In8.Cu" signal "VCC")
		(20 "In9.Cu" signal "VCC1")
		(22 "In10.Cu" signal "GND4")
		(24 "In11.Cu" signal "IN4")
		(26 "In12.Cu" signal "GND5")
		(28 "In13.Cu" signal "IN5")
		(30 "In14.Cu" signal "GND6")
		(32 "In15.Cu" signal "IN6")
		(34 "In16.Cu" signal "GND7")
		(2 "B.Cu" signal "BOTTOM")
		(9 "F.Adhes" user "F.Adhesive")
		(11 "B.Adhes" user "B.Adhesive")
		(13 "F.Paste" user "Package Geometry/Pastemask Top")
		(15 "B.Paste" user "Package Geometry/Pastemask Bottom")
		(5 "F.SilkS" user "Ref Des/Silkscreen Top")
		(7 "B.SilkS" user "Ref Des/Silkscreen Bottom")
		(1 "F.Mask" user "Board Geometry/Soldermask Top")
		(3 "B.Mask" user "Board Geometry/Soldermask Bottom")
		(17 "Dwgs.User" user "User.Drawings")
		(19 "Cmts.User" user "User.Comments")
		(21 "Eco1.User" user "User.Eco1")
		(23 "Eco2.User" user "User.Eco2")
		(25 "Edge.Cuts" user "Board Geometry/Outline")
		(27 "Margin" user)
		(31 "F.CrtYd" user "Package Geometry/Place Bound Top")
		(29 "B.CrtYd" user "Package Geometry/Place Bound Bottom")
		(35 "F.Fab" user "Ref Des/Assembly Top")
		(33 "B.Fab" user "Ref Des/Assembly Bottom")
	)
	(footprint ""
		(layer "B.Cu")
		(at 171.577 -98.135948 90)
		(property "Reference" "R6021"
			(at 0 0 90)
			(layer "B.SilkS")
			(hide yes)
			(effects
				(font
					(size 1.27 1.27)
				)
				(justify mirror)
			)
		)
		(property "Value" ""
			(at 0 0 90)
			(layer "B.Fab")
			(effects
				(font
					(size 1.27 1.27)
				)
				(justify mirror)
			)
		)
		(duplicate_pad_numbers_are_jumpers no)
		(fp_line
			(start 0.7874 -0.4064)
			(end -0.7874 -0.4064)
			(stroke
				(width 0.1524)
				(type default)
			)
			(layer "B.SilkS")
		)
		(fp_line
			(start -0.7874 -0.4064)
			(end -0.7874 0.4064)
			(stroke
				(width 0.1524)
				(type default)
			)
			(layer "B.SilkS")
		)
		(fp_line
			(start 0.7874 0.4064)
			(end 0.7874 -0.4064)
			(stroke
				(width 0.1524)
				(type default)
			)
			(layer "B.SilkS")
		)
		(fp_line
			(start -0.7874 0.4064)
			(end 0.7874 0.4064)
			(stroke
				(width 0.1524)
				(type default)
			)
			(layer "B.SilkS")
		)
		(fp_line
			(start 0.67945 -0.305054)
			(end 0.12065 -0.305054)
			(stroke
				(width 0.1)
				(type default)
			)
			(layer "B.Fab")
		)
		(fp_line
			(start 0.12065 -0.305054)
			(end 0.12065 -0.2794)
			(stroke
				(width 0.1)
				(type default)
			)
			(layer "B.Fab")
		)
		(fp_line
			(start -0.12065 -0.3048)
			(end -0.67945 -0.3048)
			(stroke
				(width 0.1)
				(type default)
			)
			(layer "B.Fab")
		)
		(fp_line
			(start -0.67945 -0.3048)
			(end -0.67945 0.3048)
			(stroke
				(width 0.1)
				(type default)
			)
			(layer "B.Fab")
		)
		(fp_line
			(start 0.12065 -0.2794)
			(end -0.12065 -0.2794)
			(stroke
				(width 0.1)
				(type default)
			)
			(layer "B.Fab")
		)
		(fp_line
			(start -0.12065 -0.2794)
			(end -0.12065 -0.3048)
			(stroke
				(width 0.1)
				(type default)
			)
			(layer "B.Fab")
		)
		(fp_line
			(start 0.12065 0.2794)
			(end 0.12065 0.3048)
			(stroke
				(width 0.1)
				(type default)
			)
			(layer "B.Fab")
		)
		(fp_line
			(start -0.120396 0.2794)
			(end 0.12065 0.2794)
			(stroke
				(width 0.1)
				(type default)
			)
			(layer "B.Fab")
		)
		(fp_line
			(start 0.67945 0.3048)
			(end 0.67945 -0.305054)
			(stroke
				(width 0.1)
				(type default)
			)
			(layer "B.Fab")
		)
		(fp_line
			(start 0.12065 0.3048)
			(end 0.67945 0.3048)
			(stroke
				(width 0.1)
				(type default)
			)
			(layer "B.Fab")
		)
		(fp_line
			(start -0.120396 0.3048)
			(end -0.120396 0.2794)
			(stroke
				(width 0.1)
				(type default)
			)
			(layer "B.Fab")
		)
		(fp_line
			(start -0.67945 0.3048)
			(end -0.120396 0.3048)
			(stroke
				(width 0.1)
				(type default)
			)
			(layer "B.Fab")
		)
		(pad "1" smd circle
			(at 0.40005 0 270)
			(size 0 0)
			(layers "B.Cu" "B.Mask" "B.Paste")
			(net "P3V3_AUX")
		)
		(pad "2" smd circle
			(at -0.40005 0 270)
			(size 0 0)
			(layers "B.Cu" "B.Mask" "B.Paste")
			(net "SGPIO_SCM_CLK_<1>")
		)
	)
	(footprint ""
		(layer "B.Cu")
		(at 156.222446 -408.517344 90)
		(property "Reference" "C6752"
			(at 0 0 90)
			(layer "B.SilkS")
			(hide yes)
			(effects
				(font
					(size 1.27 1.27)
				)
				(justify mirror)
			)
		)
		(property "Value" ""
			(at 0 0 90)
			(layer "B.Fab")
			(effects
				(font
					(size 1.27 1.27)
				)
				(justify mirror)
			)
		)
		(duplicate_pad_numbers_are_jumpers no)
		(fp_line
			(start 0.299974 -0.150114)
			(end -0.299974 -0.150114)
			(stroke
				(width 0.1)
				(type default)
			)
			(layer "B.Fab")
		)
		(fp_line
			(start -0.299974 -0.150114)
			(end -0.299974 0.150114)
			(stroke
				(width 0.1)
				(type default)
			)
			(layer "B.Fab")
		)
		(fp_line
			(start 0.299974 0.150114)
			(end 0.299974 -0.150114)
			(stroke
				(width 0.1)
				(type default)
			)
			(layer "B.Fab")
		)
		(fp_line
			(start -0.299974 0.150114)
			(end 0.299974 0.150114)
			(stroke
				(width 0.1)
				(type default)
			)
			(layer "B.Fab")
		)
		(pad "1" smd rect
			(at 0.2667 0 270)
			(size 0.3048 0.381)
			(layers "B.Cu" "B.Mask" "B.Paste")
			(net "P5E_CPU1_P3_TX_BUF_C_DN<13>")
		)
		(pad "2" smd rect
			(at -0.2667 0 270)
			(size 0.3048 0.381)
			(layers "B.Cu" "B.Mask" "B.Paste")
			(net "P5E_CPU1_P3_TX_BUF_DN<13>")
		)
	)
	(footprint ""
		(layer "B.Cu")
		(at 76.271882 -176.566576 90)
		(property "Reference" "PR201"
			(at 0 0 90)
			(layer "B.SilkS")
			(hide yes)
			(effects
				(font
					(size 1.27 1.27)
				)
				(justify mirror)
			)
		)
		(property "Value" ""
			(at 0 0 90)
			(layer "B.Fab")
			(effects
				(font
					(size 1.27 1.27)
				)
				(justify mirror)
			)
		)
		(duplicate_pad_numbers_are_jumpers no)
		(fp_line
			(start 0.7874 -0.4064)
			(end -0.7874 -0.4064)
			(stroke
				(width 0.1524)
				(type default)
			)
			(layer "B.SilkS")
		)
		(fp_line
			(start -0.7874 -0.4064)
			(end -0.7874 0.4064)
			(stroke
				(width 0.1524)
				(type default)
			)
			(layer "B.SilkS")
		)
		(fp_line
			(start 0.7874 0.4064)
			(end 0.7874 -0.4064)
			(stroke
				(width 0.1524)
				(type default)
			)
			(layer "B.SilkS")
		)
		(fp_line
			(start -0.7874 0.4064)
			(end 0.7874 0.4064)
			(stroke
				(width 0.1524)
				(type default)
			)
			(layer "B.SilkS")
		)
		(fp_line
			(start 0.67945 -0.305054)
			(end 0.12065 -0.305054)
			(stroke
				(width 0.1)
				(type default)
			)
			(layer "B.Fab")
		)
		(fp_line
			(start 0.12065 -0.305054)
			(end 0.12065 -0.2794)
			(stroke
				(width 0.1)
				(type default)
			)
			(layer "B.Fab")
		)
		(fp_line
			(start -0.12065 -0.3048)
			(end -0.67945 -0.3048)
			(stroke
				(width 0.1)
				(type default)
			)
			(layer "B.Fab")
		)
		(fp_line
			(start -0.67945 -0.3048)
			(end -0.67945 0.3048)
			(stroke
				(width 0.1)
				(type default)
			)
			(layer "B.Fab")
		)
		(fp_line
			(start 0.12065 -0.2794)
			(end -0.12065 -0.2794)
			(stroke
				(width 0.1)
				(type default)
			)
			(layer "B.Fab")
		)
		(fp_line
			(start -0.12065 -0.2794)
			(end -0.12065 -0.3048)
			(stroke
				(width 0.1)
				(type default)
			)
			(layer "B.Fab")
		)
		(fp_line
			(start 0.12065 0.2794)
			(end 0.12065 0.3048)
			(stroke
				(width 0.1)
				(type default)
			)
			(layer "B.Fab")
		)
		(fp_line
			(start -0.120396 0.2794)
			(end 0.12065 0.2794)
			(stroke
				(width 0.1)
				(type default)
			)
			(layer "B.Fab")
		)
		(fp_line
			(start 0.67945 0.3048)
			(end 0.67945 -0.305054)
			(stroke
				(width 0.1)
				(type default)
			)
			(layer "B.Fab")
		)
		(fp_line
			(start 0.12065 0.3048)
			(end 0.67945 0.3048)
			(stroke
				(width 0.1)
				(type default)
			)
			(layer "B.Fab")
		)
		(fp_line
			(start -0.120396 0.3048)
			(end -0.120396 0.2794)
			(stroke
				(width 0.1)
				(type default)
			)
			(layer "B.Fab")
		)
		(fp_line
			(start -0.67945 0.3048)
			(end -0.120396 0.3048)
			(stroke
				(width 0.1)
				(type default)
			)
			(layer "B.Fab")
		)
		(pad "1" smd circle
			(at 0.40005 0 270)
			(size 0 0)
			(layers "B.Cu" "B.Mask" "B.Paste")
			(net "PVDDCR_CPU0_P1_PVCC")
		)
		(pad "2" smd circle
			(at -0.40005 0 270)
			(size 0 0)
			(layers "B.Cu" "B.Mask" "B.Paste")
			(net "PVDDCR_CPU0_P1_VCC5")
		)
	)
	(footprint ""
		(layer "B.Cu")
		(at 410.346144 -396.393162 -90)
		(property "Reference" "C677"
			(at 0 0 90)
			(layer "B.SilkS")
			(hide yes)
			(effects
				(font
					(size 1.27 1.27)
				)
				(justify mirror)
			)
		)
		(property "Value" ""
			(at 0 0 90)
			(layer "B.Fab")
			(effects
				(font
					(size 1.27 1.27)
				)
				(justify mirror)
			)
		)
		(duplicate_pad_numbers_are_jumpers no)
		(fp_line
			(start -0.299974 0.150114)
			(end 0.299974 0.150114)
			(stroke
				(width 0.1)
				(type default)
			)
			(layer "B.Fab")
		)
		(fp_line
			(start 0.299974 0.150114)
			(end 0.299974 -0.150114)
			(stroke
				(width 0.1)
				(type default)
			)
			(layer "B.Fab")
		)
		(fp_line
			(start -0.299974 -0.150114)
			(end -0.299974 0.150114)
			(stroke
				(width 0.1)
				(type default)
			)
			(layer "B.Fab")
		)
		(fp_line
			(start 0.299974 -0.150114)
			(end -0.299974 -0.150114)
			(stroke
				(width 0.1)
				(type default)
			)
			(layer "B.Fab")
		)
		(pad "1" smd rect
			(at 0.2667 0 90)
			(size 0.3048 0.381)
			(layers "B.Cu" "B.Mask" "B.Paste")
			(net "P1V8_CPU0_RT2_1A")
		)
		(pad "2" smd rect
			(at -0.2667 0 90)
			(size 0.3048 0.381)
			(layers "B.Cu" "B.Mask" "B.Paste")
			(net "GND")
		)
	)
	(footprint ""
		(layer "B.Cu")
		(at 322.370958 -203.917296 90)
		(property "Reference" "R442"
			(at 0 0 90)
			(layer "B.SilkS")
			(hide yes)
			(effects
				(font
					(size 1.27 1.27)
				)
				(justify mirror)
			)
		)
		(property "Value" ""
			(at 0 0 90)
			(layer "B.Fab")
			(effects
				(font
					(size 1.27 1.27)
				)
				(justify mirror)
			)
		)
		(duplicate_pad_numbers_are_jumpers no)
		(fp_line
			(start 0.7874 -0.4064)
			(end -0.7874 -0.4064)
			(stroke
				(width 0.1524)
				(type default)
			)
			(layer "B.SilkS")
		)
		(fp_line
			(start -0.7874 -0.4064)
			(end -0.7874 0.4064)
			(stroke
				(width 0.1524)
				(type default)
			)
			(layer "B.SilkS")
		)
		(fp_line
			(start 0.7874 0.4064)
			(end 0.7874 -0.4064)
			(stroke
				(width 0.1524)
				(type default)
			)
			(layer "B.SilkS")
		)
		(fp_line
			(start -0.7874 0.4064)
			(end 0.7874 0.4064)
			(stroke
				(width 0.1524)
				(type default)
			)
			(layer "B.SilkS")
		)
		(fp_line
			(start 0.67945 -0.305054)
			(end 0.12065 -0.305054)
			(stroke
				(width 0.1)
				(type default)
			)
			(layer "B.Fab")
		)
		(fp_line
			(start 0.12065 -0.305054)
			(end 0.12065 -0.2794)
			(stroke
				(width 0.1)
				(type default)
			)
			(layer "B.Fab")
		)
		(fp_line
			(start -0.12065 -0.3048)
			(end -0.67945 -0.3048)
			(stroke
				(width 0.1)
				(type default)
			)
			(layer "B.Fab")
		)
		(fp_line
			(start -0.67945 -0.3048)
			(end -0.67945 0.3048)
			(stroke
				(width 0.1)
				(type default)
			)
			(layer "B.Fab")
		)
		(fp_line
			(start 0.12065 -0.2794)
			(end -0.12065 -0.2794)
			(stroke
				(width 0.1)
				(type default)
			)
			(layer "B.Fab")
		)
		(fp_line
			(start -0.12065 -0.2794)
			(end -0.12065 -0.3048)
			(stroke
				(width 0.1)
				(type default)
			)
			(layer "B.Fab")
		)
		(fp_line
			(start 0.12065 0.2794)
			(end 0.12065 0.3048)
			(stroke
				(width 0.1)
				(type default)
			)
			(layer "B.Fab")
		)
		(fp_line
			(start -0.120396 0.2794)
			(end 0.12065 0.2794)
			(stroke
				(width 0.1)
				(type default)
			)
			(layer "B.Fab")
		)
		(fp_line
			(start 0.67945 0.3048)
			(end 0.67945 -0.305054)
			(stroke
				(width 0.1)
				(type default)
			)
			(layer "B.Fab")
		)
		(fp_line
			(start 0.12065 0.3048)
			(end 0.67945 0.3048)
			(stroke
				(width 0.1)
				(type default)
			)
			(layer "B.Fab")
		)
		(fp_line
			(start -0.120396 0.3048)
			(end -0.120396 0.2794)
			(stroke
				(width 0.1)
				(type default)
			)
			(layer "B.Fab")
		)
		(fp_line
			(start -0.67945 0.3048)
			(end -0.120396 0.3048)
			(stroke
				(width 0.1)
				(type default)
			)
			(layer "B.Fab")
		)
		(pad "1" smd circle
			(at 0.40005 0 270)
			(size 0 0)
			(layers "B.Cu" "B.Mask" "B.Paste")
			(net "RST_CPU0_RESETL_N")
		)
		(pad "2" smd circle
			(at -0.40005 0 270)
			(size 0 0)
			(layers "B.Cu" "B.Mask" "B.Paste")
			(net "PVDD18_S5_P0")
		)
	)
	(footprint ""
		(layer "B.Cu")
		(at 26.289762 -347.780356 -90)
		(property "Reference" "PR370"
			(at 0 0 90)
			(layer "B.SilkS")
			(hide yes)
			(effects
				(font
					(size 1.27 1.27)
				)
				(justify mirror)
			)
		)
		(property "Value" ""
			(at 0 0 90)
			(layer "B.Fab")
			(effects
				(font
					(size 1.27 1.27)
				)
				(justify mirror)
			)
		)
		(duplicate_pad_numbers_are_jumpers no)
		(fp_line
			(start -0.7874 0.4064)
			(end 0.7874 0.4064)
			(stroke
				(width 0.1524)
				(type default)
			)
			(layer "B.SilkS")
		)
		(fp_line
			(start 0.7874 0.4064)
			(end 0.7874 -0.4064)
			(stroke
				(width 0.1524)
				(type default)
			)
			(layer "B.SilkS")
		)
		(fp_line
			(start -0.7874 -0.4064)
			(end -0.7874 0.4064)
			(stroke
				(width 0.1524)
				(type default)
			)
			(layer "B.SilkS")
		)
		(fp_line
			(start 0.7874 -0.4064)
			(end -0.7874 -0.4064)
			(stroke
				(width 0.1524)
				(type default)
			)
			(layer "B.SilkS")
		)
		(fp_line
			(start -0.67945 0.3048)
			(end -0.120396 0.3048)
			(stroke
				(width 0.1)
				(type default)
			)
			(layer "B.Fab")
		)
		(fp_line
			(start -0.120396 0.3048)
			(end -0.120396 0.2794)
			(stroke
				(width 0.1)
				(type default)
			)
			(layer "B.Fab")
		)
		(fp_line
			(start 0.12065 0.3048)
			(end 0.67945 0.3048)
			(stroke
				(width 0.1)
				(type default)
			)
			(layer "B.Fab")
		)
		(fp_line
			(start 0.67945 0.3048)
			(end 0.67945 -0.305054)
			(stroke
				(width 0.1)
				(type default)
			)
			(layer "B.Fab")
		)
		(fp_line
			(start -0.120396 0.2794)
			(end 0.12065 0.2794)
			(stroke
				(width 0.1)
				(type default)
			)
			(layer "B.Fab")
		)
		(fp_line
			(start 0.12065 0.2794)
			(end 0.12065 0.3048)
			(stroke
				(width 0.1)
				(type default)
			)
			(layer "B.Fab")
		)
		(fp_line
			(start -0.12065 -0.2794)
			(end -0.12065 -0.3048)
			(stroke
				(width 0.1)
				(type default)
			)
			(layer "B.Fab")
		)
		(fp_line
			(start 0.12065 -0.2794)
			(end -0.12065 -0.2794)
			(stroke
				(width 0.1)
				(type default)
			)
			(layer "B.Fab")
		)
		(fp_line
			(start -0.67945 -0.3048)
			(end -0.67945 0.3048)
			(stroke
				(width 0.1)
				(type default)
			)
			(layer "B.Fab")
		)
		(fp_line
			(start -0.12065 -0.3048)
			(end -0.67945 -0.3048)
			(stroke
				(width 0.1)
				(type default)
			)
			(layer "B.Fab")
		)
		(fp_line
			(start 0.12065 -0.305054)
			(end 0.12065 -0.2794)
			(stroke
				(width 0.1)
				(type default)
			)
			(layer "B.Fab")
		)
		(fp_line
			(start 0.67945 -0.305054)
			(end 0.12065 -0.305054)
			(stroke
				(width 0.1)
				(type default)
			)
			(layer "B.Fab")
		)
		(pad "1" smd circle
			(at 0.40005 0 90)
			(size 0 0)
			(layers "B.Cu" "B.Mask" "B.Paste")
			(net "PVDDCR_CPU1_P1_PVCC")
		)
		(pad "2" smd circle
			(at -0.40005 0 90)
			(size 0 0)
			(layers "B.Cu" "B.Mask" "B.Paste")
			(net "PVDDIO_P1_VCC4")
		)
	)
	(footprint ""
		(layer "B.Cu")
		(at 296.703496 -349.381572 -90)
		(property "Reference" "PR103"
			(at 0 0 90)
			(layer "B.SilkS")
			(hide yes)
			(effects
				(font
					(size 1.27 1.27)
				)
				(justify mirror)
			)
		)
		(property "Value" ""
			(at 0 0 90)
			(layer "B.Fab")
			(effects
				(font
					(size 1.27 1.27)
				)
				(justify mirror)
			)
		)
		(duplicate_pad_numbers_are_jumpers no)
		(fp_line
			(start -0.7874 0.4064)
			(end 0.7874 0.4064)
			(stroke
				(width 0.1524)
				(type default)
			)
			(layer "B.SilkS")
		)
		(fp_line
			(start 0.7874 0.4064)
			(end 0.7874 -0.4064)
			(stroke
				(width 0.1524)
				(type default)
			)
			(layer "B.SilkS")
		)
		(fp_line
			(start -0.7874 -0.4064)
			(end -0.7874 0.4064)
			(stroke
				(width 0.1524)
				(type default)
			)
			(layer "B.SilkS")
		)
		(fp_line
			(start 0.7874 -0.4064)
			(end -0.7874 -0.4064)
			(stroke
				(width 0.1524)
				(type default)
			)
			(layer "B.SilkS")
		)
		(fp_line
			(start -0.67945 0.3048)
			(end -0.120396 0.3048)
			(stroke
				(width 0.1)
				(type default)
			)
			(layer "B.Fab")
		)
		(fp_line
			(start -0.120396 0.3048)
			(end -0.120396 0.2794)
			(stroke
				(width 0.1)
				(type default)
			)
			(layer "B.Fab")
		)
		(fp_line
			(start 0.12065 0.3048)
			(end 0.67945 0.3048)
			(stroke
				(width 0.1)
				(type default)
			)
			(layer "B.Fab")
		)
		(fp_line
			(start 0.67945 0.3048)
			(end 0.67945 -0.305054)
			(stroke
				(width 0.1)
				(type default)
			)
			(layer "B.Fab")
		)
		(fp_line
			(start -0.120396 0.2794)
			(end 0.12065 0.2794)
			(stroke
				(width 0.1)
				(type default)
			)
			(layer "B.Fab")
		)
		(fp_line
			(start 0.12065 0.2794)
			(end 0.12065 0.3048)
			(stroke
				(width 0.1)
				(type default)
			)
			(layer "B.Fab")
		)
		(fp_line
			(start -0.12065 -0.2794)
			(end -0.12065 -0.3048)
			(stroke
				(width 0.1)
				(type default)
			)
			(layer "B.Fab")
		)
		(fp_line
			(start 0.12065 -0.2794)
			(end -0.12065 -0.2794)
			(stroke
				(width 0.1)
				(type default)
			)
			(layer "B.Fab")
		)
		(fp_line
			(start -0.67945 -0.3048)
			(end -0.67945 0.3048)
			(stroke
				(width 0.1)
				(type default)
			)
			(layer "B.Fab")
		)
		(fp_line
			(start -0.12065 -0.3048)
			(end -0.67945 -0.3048)
			(stroke
				(width 0.1)
				(type default)
			)
			(layer "B.Fab")
		)
		(fp_line
			(start 0.12065 -0.305054)
			(end 0.12065 -0.2794)
			(stroke
				(width 0.1)
				(type default)
			)
			(layer "B.Fab")
		)
		(fp_line
			(start 0.67945 -0.305054)
			(end 0.12065 -0.305054)
			(stroke
				(width 0.1)
				(type default)
			)
			(layer "B.Fab")
		)
		(pad "1" smd circle
			(at 0.40005 0 90)
			(size 0 0)
			(layers "B.Cu" "B.Mask" "B.Paste")
			(net "PVDDIO_P0_VOS1")
		)
		(pad "2" smd circle
			(at -0.40005 0 90)
			(size 0 0)
			(layers "B.Cu" "B.Mask" "B.Paste")
			(net "PVDDIO_P0")
		)
	)
)
